# S9S_MB_2U (Grand Teton) — schematic netlist excerpt (pin names and nets, part order shuffled) for the footprints in the layout excerpt that follows; sources: Cadence DE-HDL packaged netlist, KiCad conversion of 03242023_DA0F0TMBIJ0_F0T_Motherboard_J_brd_V01_OCP.brd

R3191  Q_RES  33.2 1% CHIP  pkg 0402LF  page 161 : A = OCP_V3_2_PWRBRK_BUFF_N ; B = OCP_V3_2_PWRBRK_N
R3627  Q_RES  4.7K 1% CHIP  pkg 0402LF  page 171 : A = P3V3_AUX ; B = INA230_1_A0

(kicad_pcb
	(version 20260206)
	(generator "pcbnew")
	(generator_version "10.0")
	(general
		(thickness 1.6)
		(legacy_teardrops no)
	)
	(paper "A4")
	(title_block
		(title "03242023_DA0F0TMBIJ0_F0T_Motherboard_J_brd_V01_OCP.brd")
		(comment 1 "Grand Teton / footprints 2158-2159 of 6105")
	)
	(layers
		(0 "F.Cu" signal "TOP")
		(4 "In1.Cu" signal "GND")
		(6 "In2.Cu" signal "IN1")
		(8 "In3.Cu" signal "GND1")
		(10 "In4.Cu" signal "IN2")
		(12 "In5.Cu" signal "GND2")
		(14 "In6.Cu" signal "IN3")
		(16 "In7.Cu" signal "GND3")
		(18 "In8.Cu" signal "VCC")
		(20 "In9.Cu" signal "VCC1")
		(22 "In10.Cu" signal "GND4")
		(24 "In11.Cu" signal "IN4")
		(26 "In12.Cu" signal "GND5")
		(28 "In13.Cu" signal "IN5")
		(30 "In14.Cu" signal "GND6")
		(32 "In15.Cu" signal "IN6")
		(34 "In16.Cu" signal "GND7")
		(2 "B.Cu" signal "BOTTOM")
		(9 "F.Adhes" user "F.Adhesive")
		(11 "B.Adhes" user "B.Adhesive")
		(13 "F.Paste" user "Package Geometry/Pastemask Top")
		(15 "B.Paste" user "Package Geometry/Pastemask Bottom")
		(5 "F.SilkS" user "Ref Des/Silkscreen Top")
		(7 "B.SilkS" user "Ref Des/Silkscreen Bottom")
		(1 "F.Mask" user "Board Geometry/Soldermask Top")
		(3 "B.Mask" user "Board Geometry/Soldermask Bottom")
		(17 "Dwgs.User" user "User.Drawings")
		(19 "Cmts.User" user "User.Comments")
		(21 "Eco1.User" user "User.Eco1")
		(23 "Eco2.User" user "User.Eco2")
		(25 "Edge.Cuts" user "Board Geometry/Outline")
		(27 "Margin" user)
		(31 "F.CrtYd" user "Package Geometry/Place Bound Top")
		(29 "B.CrtYd" user "Package Geometry/Place Bound Bottom")
		(35 "F.Fab" user "Ref Des/Assembly Top")
		(33 "B.Fab" user "Ref Des/Assembly Bottom")
	)
	(footprint ""
		(layer "F.Cu")
		(at 116.367306 -29.450792)
		(property "Reference" "R3191"
			(at 0 0 0)
			(layer "F.SilkS")
			(hide yes)
			(effects
				(font
					(size 1.27 1.27)
				)
			)
		)
		(property "Value" ""
			(at 0 0 0)
			(layer "F.Fab")
			(effects
				(font
					(size 1.27 1.27)
				)
			)
		)
		(duplicate_pad_numbers_are_jumpers no)
		(fp_line
			(start -0.7874 -0.4064)
			(end 0.7874 -0.4064)
			(stroke
				(width 0.1524)
				(type default)
			)
			(layer "F.SilkS")
		)
		(fp_line
			(start -0.7874 0.4064)
			(end -0.7874 -0.4064)
			(stroke
				(width 0.1524)
				(type default)
			)
			(layer "F.SilkS")
		)
		(fp_line
			(start 0.7874 -0.4064)
			(end 0.7874 0.4064)
			(stroke
				(width 0.1524)
				(type default)
			)
			(layer "F.SilkS")
		)
		(fp_line
			(start 0.7874 0.4064)
			(end -0.7874 0.4064)
			(stroke
				(width 0.1524)
				(type default)
			)
			(layer "F.SilkS")
		)
		(fp_line
			(start -0.67945 -0.305054)
			(end -0.12065 -0.305054)
			(stroke
				(width 0.1)
				(type default)
			)
			(layer "F.Fab")
		)
		(fp_line
			(start -0.67945 0.3048)
			(end -0.67945 -0.305054)
			(stroke
				(width 0.1)
				(type default)
			)
			(layer "F.Fab")
		)
		(fp_line
			(start -0.12065 -0.305054)
			(end -0.12065 -0.2794)
			(stroke
				(width 0.1)
				(type default)
			)
			(layer "F.Fab")
		)
		(fp_line
			(start -0.12065 -0.2794)
			(end 0.12065 -0.2794)
			(stroke
				(width 0.1)
				(type default)
			)
			(layer "F.Fab")
		)
		(fp_line
			(start -0.12065 0.2794)
			(end -0.12065 0.3048)
			(stroke
				(width 0.1)
				(type default)
			)
			(layer "F.Fab")
		)
		(fp_line
			(start -0.12065 0.3048)
			(end -0.67945 0.3048)
			(stroke
				(width 0.1)
				(type default)
			)
			(layer "F.Fab")
		)
		(fp_line
			(start 0.120396 0.2794)
			(end -0.12065 0.2794)
			(stroke
				(width 0.1)
				(type default)
			)
			(layer "F.Fab")
		)
		(fp_line
			(start 0.120396 0.3048)
			(end 0.120396 0.2794)
			(stroke
				(width 0.1)
				(type default)
			)
			(layer "F.Fab")
		)
		(fp_line
			(start 0.12065 -0.3048)
			(end 0.67945 -0.3048)
			(stroke
				(width 0.1)
				(type default)
			)
			(layer "F.Fab")
		)
		(fp_line
			(start 0.12065 -0.2794)
			(end 0.12065 -0.3048)
			(stroke
				(width 0.1)
				(type default)
			)
			(layer "F.Fab")
		)
		(fp_line
			(start 0.67945 -0.3048)
			(end 0.67945 0.3048)
			(stroke
				(width 0.1)
				(type default)
			)
			(layer "F.Fab")
		)
		(fp_line
			(start 0.67945 0.3048)
			(end 0.120396 0.3048)
			(stroke
				(width 0.1)
				(type default)
			)
			(layer "F.Fab")
		)
		(pad "1" smd circle
			(at -0.40005 0)
			(size 0 0)
			(layers "F.Cu" "F.Mask" "F.Paste")
			(net "OCP_V3_2_PWRBRK_BUFF_N")
		)
		(pad "2" smd circle
			(at 0.40005 0)
			(size 0 0)
			(layers "F.Cu" "F.Mask" "F.Paste")
			(net "OCP_V3_2_PWRBRK_N")
		)
	)
	(footprint ""
		(layer "F.Cu")
		(at 445.157098 -93.484192 180)
		(property "Reference" "R3627"
			(at 0 0 180)
			(layer "F.SilkS")
			(hide yes)
			(effects
				(font
					(size 1.27 1.27)
				)
			)
		)
		(property "Value" ""
			(at 0 0 180)
			(layer "F.Fab")
			(effects
				(font
					(size 1.27 1.27)
				)
			)
		)
		(duplicate_pad_numbers_are_jumpers no)
		(fp_line
			(start 0.7874 0.4064)
			(end -0.7874 0.4064)
			(stroke
				(width 0.1524)
				(type default)
			)
			(layer "F.SilkS")
		)
		(fp_line
			(start 0.7874 -0.4064)
			(end 0.7874 0.4064)
			(stroke
				(width 0.1524)
				(type default)
			)
			(layer "F.SilkS")
		)
		(fp_line
			(start -0.7874 0.4064)
			(end -0.7874 -0.4064)
			(stroke
				(width 0.1524)
				(type default)
			)
			(layer "F.SilkS")
		)
		(fp_line
			(start -0.7874 -0.4064)
			(end 0.7874 -0.4064)
			(stroke
				(width 0.1524)
				(type default)
			)
			(layer "F.SilkS")
		)
		(fp_line
			(start 0.67945 0.3048)
			(end 0.120396 0.3048)
			(stroke
				(width 0.1)
				(type default)
			)
			(layer "F.Fab")
		)
		(fp_line
			(start 0.67945 -0.3048)
			(end 0.67945 0.3048)
			(stroke
				(width 0.1)
				(type default)
			)
			(layer "F.Fab")
		)
		(fp_line
			(start 0.12065 -0.2794)
			(end 0.12065 -0.3048)
			(stroke
				(width 0.1)
				(type default)
			)
			(layer "F.Fab")
		)
		(fp_line
			(start 0.12065 -0.3048)
			(end 0.67945 -0.3048)
			(stroke
				(width 0.1)
				(type default)
			)
			(layer "F.Fab")
		)
		(fp_line
			(start 0.120396 0.3048)
			(end 0.120396 0.2794)
			(stroke
				(width 0.1)
				(type default)
			)
			(layer "F.Fab")
		)
		(fp_line
			(start 0.120396 0.2794)
			(end -0.12065 0.2794)
			(stroke
				(width 0.1)
				(type default)
			)
			(layer "F.Fab")
		)
		(fp_line
			(start -0.12065 0.3048)
			(end -0.67945 0.3048)
			(stroke
				(width 0.1)
				(type default)
			)
			(layer "F.Fab")
		)
		(fp_line
			(start -0.12065 0.2794)
			(end -0.12065 0.3048)
			(stroke
				(width 0.1)
				(type default)
			)
			(layer "F.Fab")
		)
		(fp_line
			(start -0.12065 -0.2794)
			(end 0.12065 -0.2794)
			(stroke
				(width 0.1)
				(type default)
			)
			(layer "F.Fab")
		)
		(fp_line
			(start -0.12065 -0.305054)
			(end -0.12065 -0.2794)
			(stroke
				(width 0.1)
				(type default)
			)
			(layer "F.Fab")
		)
		(fp_line
			(start -0.67945 0.3048)
			(end -0.67945 -0.305054)
			(stroke
				(width 0.1)
				(type default)
			)
			(layer "F.Fab")
		)
		(fp_line
			(start -0.67945 -0.305054)
			(end -0.12065 -0.305054)
			(stroke
				(width 0.1)
				(type default)
			)
			(layer "F.Fab")
		)
		(pad "1" smd circle
			(at -0.40005 0 180)
			(size 0 0)
			(layers "F.Cu" "F.Mask" "F.Paste")
			(net "P3V3_AUX")
		)
		(pad "2" smd circle
			(at 0.40005 0 180)
			(size 0 0)
			(layers "F.Cu" "F.Mask" "F.Paste")
			(net "INA230_1_A0")
		)
	)
)
